# S9S_MB_2U (Grand Teton) — schematic netlist excerpt (pin names and nets, part order shuffled) for the footprints in the layout excerpt that follows; sources: Cadence DE-HDL packaged netlist, KiCad conversion of 03242023_DA0F0TMBIJ0_F0T_Motherboard_J_brd_V01_OCP.brd

J32  SCONN288_ADR50017P087CC  SCONN288_ADR50017-P087CC IO  pkg DDR288S_1-1VXB  page 113
  VIN_BULK0  = P12V_S3_AUX_CPU1_NVDIMM
  RFU0  = TP_CHH_CPU1_DIMM2_FRU_0
  VIN_MGMT  = P3V3_AUX
  HSCL  = I3C_SPD_DDREFGH_CPU1_LVC1_SCL_7
  HSDA  = I3C_SPD_DDREFGH_CPU1_LVC1_SDA
  VSS0  = GND
  DQ0_A  = M_H_CPU1_SA_DQ<0>
  VSS1  = GND
  DQ1_A  = M_H_CPU1_SA_DQ<1>
  VSS2  = GND
  DQS0_A_T  = M_H_CPU1_SA_DQS_DP<0>
  DQS0_A_C  = M_H_CPU1_SA_DQS_DN<0>
  VSS3  = GND
  DQ4_A  = M_H_CPU1_SA_DQ<4>
  VSS4  = GND
  DQ5_A  = M_H_CPU1_SA_DQ<5>
  VSS5  = GND
  DQ8_A  = M_H_CPU1_SA_DQ<8>
  VSS6  = GND
  DQ9_A  = M_H_CPU1_SA_DQ<9>
  VSS7  = GND
  DQS1_A_T  = M_H_CPU1_SA_DQS_DP<1>
  DQS1_A_C  = M_H_CPU1_SA_DQS_DN<1>
  VSS8  = GND
  DQ12_A  = M_H_CPU1_SA_DQ<12>
  VSS9  = GND
  DQ13_A  = M_H_CPU1_SA_DQ<13>
  VSS10  = GND
  DQ16_A  = M_H_CPU1_SA_DQ<16>
  VSS11  = GND
  DQ17_A  = M_H_CPU1_SA_DQ<17>
  VSS12  = GND
  DQS2_A_T  = M_H_CPU1_SA_DQS_DP<2>
  DQS2_A_C  = M_H_CPU1_SA_DQS_DN<2>
  VSS13  = GND
  DQ20_A  = M_H_CPU1_SA_DQ<20>
  VSS14  = GND
  DQ21_A  = M_H_CPU1_SA_DQ<21>
  VSS15  = GND
  DQ24_A  = M_H_CPU1_SA_DQ<24>
  VSS16  = GND
  DQ25_A  = M_H_CPU1_SA_DQ<25>
  VSS17  = GND
  DQS3_A_T  = M_H_CPU1_SA_DQS_DP<3>
  DQS3_A_C  = M_H_CPU1_SA_DQS_DN<3>
  VSS18  = GND
  DQ28_A  = M_H_CPU1_SA_DQ<28>
  VSS19  = GND
  DQ29_A  = M_H_CPU1_SA_DQ<29>
  VSS20  = GND
  CB0_A  = M_H_CPU1_SA_CB<0>
  VSS21  = GND
  CB1_A  = M_H_CPU1_SA_CB<1>
  VSS22  = GND
  DQS4_A_T  = M_H_CPU1_SA_DQS_DP<4>
  DQS4_A_C  = M_H_CPU1_SA_DQS_DN<4>
  VSS23  = GND
  CB4_A  = M_H_CPU1_SA_CB<4>
  VSS24  = GND
  CB5_A  = M_H_CPU1_SA_CB<5>
  VSS25  = GND
  ALERT_N  = M_H_CPU1_ALERT_N
  VSS26  = GND
  CS0_A_N  = M_H_CPU1_SA_CS_N<2>
  VSS27  = GND
  CA0_A  = M_H_CPU1_SA_CA<0>
  VSS28  = GND
  CA2_A  = M_H_CPU1_SA_CA<2>
  VSS29  = GND
  CA4_A  = M_H_CPU1_SA_CA<4>
  VSS30  = GND
  CA6_A  = M_H_CPU1_SA_CA<6>
  VSS31  = GND
  PAR_A  = M_H_CPU1_SA_PAR
  VSS32  = GND
  CA0_B  = M_H_CPU1_SB_CA<0>
  VSS33  = GND
  CA2_B  = M_H_CPU1_SB_CA<2>
  VSS34  = GND
  CA4_B  = M_H_CPU1_SB_CA<4>
  VSS35  = GND
  CA6_B  = M_H_CPU1_SB_CA<6>
  VSS36  = GND
  CS0_B_N  = M_H_CPU1_SB_CS_N<2>
  VSS37  = GND
  \lbd||rsp_a_n\  = M_H_CPU1_SA_RSP<1>
  \lbs||rsp_b_n\  = M_H_CPU1_SB_RSP<1>
  VSS38  = GND
  CB4_B  = M_H_CPU1_SB_CB<4>
  VSS39  = GND
  CB5_B  = M_H_CPU1_SB_CB<5>
  VSS40  = GND
  \dqs9_b_t||tdqs9_b_t||dbi4_b_n\  = M_H_CPU1_SB_DQS_DP<9>
  \dqs9_b_c||tdqs9_b_c\  = M_H_CPU1_SB_DQS_DN<9>
  VSS41  = GND
  CB0_B  = M_H_CPU1_SB_CB<0>
  VSS42  = GND
  CB1_B  = M_H_CPU1_SB_CB<1>
  VSS43  = GND
  DQ0_B  = M_H_CPU1_SB_DQ<0>
  VSS44  = GND
  DQ1_B  = M_H_CPU1_SB_DQ<1>
  VSS45  = GND
  DQS0_B_T  = M_H_CPU1_SB_DQS_DP<0>
  DQS0_B_C  = M_H_CPU1_SB_DQS_DN<0>
  VSS46  = GND
  DQ4_B  = M_H_CPU1_SB_DQ<4>
  VSS47  = GND
  DQ5_B  = M_H_CPU1_SB_DQ<5>
  VSS48  = GND
  DQ8_B  = M_H_CPU1_SB_DQ<8>
  VSS49  = GND
  DQ9_B  = M_H_CPU1_SB_DQ<9>
  VSS50  = GND
  DQS1_B_T  = M_H_CPU1_SB_DQS_DP<1>
  DQS1_B_C  = M_H_CPU1_SB_DQS_DN<1>
  VSS51  = GND
  DQ12_B  = M_H_CPU1_SB_DQ<12>
  VSS52  = GND
  DQ13_B  = M_H_CPU1_SB_DQ<13>
  VSS53  = GND
  DQ16_B  = M_H_CPU1_SB_DQ<16>
  VSS54  = GND
  DQ17_B  = M_H_CPU1_SB_DQ<17>
  VSS55  = GND
  DQS2_B_T  = M_H_CPU1_SB_DQS_DP<2>
  DQS2_B_C  = M_H_CPU1_SB_DQS_DN<2>
  VSS56  = GND
  DQ20_B  = M_H_CPU1_SB_DQ<20>
  VSS57  = GND
  DQ21_B  = M_H_CPU1_SB_DQ<21>
  VSS58  = GND
  DQ24_B  = M_H_CPU1_SB_DQ<24>
  VSS59  = GND
  DQ25_B  = M_H_CPU1_SB_DQ<25>
  VSS60  = GND
  DQS3_B_T  = M_H_CPU1_SB_DQS_DP<3>
  DQS3_B_C  = M_H_CPU1_SB_DQS_DN<3>
  VSS61  = GND
  DQ28_B  = M_H_CPU1_SB_DQ<28>
  VSS62  = GND
  DQ29_B  = M_H_CPU1_SB_DQ<29>
  VSS63  = GND
  RFU1  = TP_CHH_CPU1_DIMM2_FRU_1
  VIN_BULK1  = P12V_S3_AUX_CPU1_NVDIMM
  VIN_BULK2  = P12V_S3_AUX_CPU1_NVDIMM
  \pwr_good||fail_n\  = PWRGD_CHH_CPU1_DIMM2
  HSA  = PD_CHH_CPU1_DIMM2_SAA
  RFU2  = TP_CHH_CPU1_DIMM2_FRU_2
  RFU3  = TP_CHH_CPU1_DIMM2_FRU_3
  VSS64  = GND
  DQ2_A  = M_H_CPU1_SA_DQ<2>
  VSS65  = GND
  DQ3_A  = M_H_CPU1_SA_DQ<3>
  VSS66  = GND
  \dqs5_a_c||tdqs5_a_c||dqs5_a_t||tdqs5_a_t\  = M_H_CPU1_SA_DQS_DN<5>
  \dqs5_a_t||tdqs5_a_t\  = M_H_CPU1_SA_DQS_DP<5>
  VSS67  = GND
  DQ6_A  = M_H_CPU1_SA_DQ<6>
  VSS68  = GND
  DQ7_A  = M_H_CPU1_SA_DQ<7>
  VSS69  = GND
  DQ10_A  = M_H_CPU1_SA_DQ<10>
  VSS70  = GND
  DQ11_A  = M_H_CPU1_SA_DQ<11>
  VSS71  = GND
  \dqs6_a_c||tdqs6_a_c||dqs6_a_t||tdqs6_a_t\  = M_H_CPU1_SA_DQS_DN<6>
  \dqs6_a_t||tdqs6_a_t\  = M_H_CPU1_SA_DQS_DP<6>
  VSS72  = GND
  DQ14_A  = M_H_CPU1_SA_DQ<14>
  VSS73  = GND
  DQ15_A  = M_H_CPU1_SA_DQ<15>
  VSS74  = GND
  DQ18_A  = M_H_CPU1_SA_DQ<18>
  VSS75  = GND
  DQ19_A  = M_H_CPU1_SA_DQ<19>
  VSS76  = GND
  \dqs7_a_c||tdqs7_a_c\  = M_H_CPU1_SA_DQS_DN<7>
  \dqs7_a_t||tdqs7_a_t\  = M_H_CPU1_SA_DQS_DP<7>
  VSS77  = GND
  DQ22_A  = M_H_CPU1_SA_DQ<22>
  VSS78  = GND
  DQ23_A  = M_H_CPU1_SA_DQ<23>
  VSS79  = GND
  DQ26_A  = M_H_CPU1_SA_DQ<26>
  VSS80  = GND
  DQ27_A  = M_H_CPU1_SA_DQ<27>
  VSS81  = GND
  \dqs8_a_c||tdqs8_a_c\  = M_H_CPU1_SA_DQS_DN<8>
  \dqs8_a_t||tdqs8_a_t\  = M_H_CPU1_SA_DQS_DP<8>
  VSS82  = GND
  DQ30_A  = M_H_CPU1_SA_DQ<30>
  VSS83  = GND
  DQ31_A  = M_H_CPU1_SA_DQ<31>
  VSS84  = GND
  CB2_A  = M_H_CPU1_SA_CB<2>
  VSS85  = GND
  CB3_A  = M_H_CPU1_SA_CB<3>
  VSS86  = GND
  \dqs9_a_c||tdqs9_a_c\  = M_H_CPU1_SA_DQS_DN<9>
  \dqs9_a_t||tdqs9_a_t\  = M_H_CPU1_SA_DQS_DP<9>
  VSS87  = GND
  CB6_A  = M_H_CPU1_SA_CB<6>
  VSS88  = GND
  CB7_A  = M_H_CPU1_SA_CB<7>
  VSS89  = GND
  RESET_N  = RST_M_GH_CPU1_FPGA_N
  VSS90  = GND
  CS1_A_N  = M_H_CPU1_SA_CS_N<3>
  VSS91  = GND
  CA1_A  = M_H_CPU1_SA_CA<1>
  VSS92  = GND
  CA3_A  = M_H_CPU1_SA_CA<3>
  VSS93  = GND
  CA5_A  = M_H_CPU1_SA_CA<5>
  VSS94  = GND
  CK_T  = M_H_CPU1_CLK_DP<1>
  CK_C  = M_H_CPU1_CLK_DN<1>
  VSS95  = GND
  RFU4  = TP_CHH_CPU1_DIMM2_FRU_4
  CA1_B  = M_H_CPU1_SB_CA<1>
  VSS96  = GND
  CA3_B  = M_H_CPU1_SB_CA<3>
  VSS97  = GND
  CA5_B  = M_H_CPU1_SB_CA<5>
  VSS98  = GND
  PAR_B  = M_H_CPU1_SB_PAR
  VSS99  = GND
  CS1_B_N  = M_H_CPU1_SB_CS_N<3>
  VSS100  = GND
  RFU5  = TP_CHH_CPU1_DIMM2_FRU_5
  RFU6  = TP_CHH_CPU1_DIMM2_FRU_6
  VSS101  = GND
  CB6_B  = M_H_CPU1_SB_CB<6>
  VSS102  = GND
  CB7_B  = M_H_CPU1_SB_CB<7>
  VSS103  = GND
  DQS4_B_C  = M_H_CPU1_SB_DQS_DN<4>
  DQS4_B_T  = M_H_CPU1_SB_DQS_DP<4>
  VSS104  = GND
  CB2_B  = M_H_CPU1_SB_CB<2>
  VSS105  = GND
  CB3_B  = M_H_CPU1_SB_CB<3>
  VSS106  = GND
  DQ2_B  = M_H_CPU1_SB_DQ<2>
  VSS107  = GND
  DQ3_B  = M_H_CPU1_SB_DQ<3>
  VSS108  = GND
  \dqs5_b_c||tdqs5_b_c\  = M_H_CPU1_SB_DQS_DN<5>
  \dqs5_b_t||tdqs5_b_t\  = M_H_CPU1_SB_DQS_DP<5>
  VSS109  = GND
  DQ6_B  = M_H_CPU1_SB_DQ<6>
  VSS110  = GND
  DQ7_B  = M_H_CPU1_SB_DQ<7>
  VSS111  = GND
  DQ10_B  = M_H_CPU1_SB_DQ<10>
  VSS112  = GND
  DQ11_B  = M_H_CPU1_SB_DQ<11>
  VSS113  = GND
  \dqs6_b_c||tdqs6_b_c\  = M_H_CPU1_SB_DQS_DN<6>
  \dqs6_b_t||tdqs6_b_t\  = M_H_CPU1_SB_DQS_DP<6>
  VSS114  = GND
  DQ14_B  = M_H_CPU1_SB_DQ<14>
  VSS115  = GND
  DQ15_B  = M_H_CPU1_SB_DQ<15>
  VSS116  = GND
  DQ18_B  = M_H_CPU1_SB_DQ<18>
  VSS117  = GND
  DQ19_B  = M_H_CPU1_SB_DQ<19>
  VSS118  = GND
  \dqs7_b_c||tdqs7_b_c\  = M_H_CPU1_SB_DQS_DN<7>
  \dqs7_b_t||tdqs7_b_t\  = M_H_CPU1_SB_DQS_DP<7>
  VSS119  = GND
  DQ22_B  = M_H_CPU1_SB_DQ<22>
  VSS120  = GND
  DQ23_B  = M_H_CPU1_SB_DQ<23>
  VSS121  = GND
  DQ26_B  = M_H_CPU1_SB_DQ<26>
  VSS122  = GND
  DQ27_B  = M_H_CPU1_SB_DQ<27>
  VSS123  = GND
  \dqs8_b_c||tdqs8_b_c\  = M_H_CPU1_SB_DQS_DN<8>
  \dqs8_b_t||tdqs8_b_t\  = M_H_CPU1_SB_DQS_DP<8>
  VSS124  = GND
  DQ30_B  = M_H_CPU1_SB_DQ<30>
  VSS125  = GND
  DQ31_B  = M_H_CPU1_SB_DQ<31>
  VSS126  = GND
  G1  = GND
  G2  = GND
  G3  = GND

(kicad_pcb
	(version 20260206)
	(generator "pcbnew")
	(generator_version "10.0")
	(general
		(thickness 1.6)
		(legacy_teardrops no)
	)
	(paper "A4")
	(title_block
		(title "03242023_DA0F0TMBIJ0_F0T_Motherboard_J_brd_V01_OCP.brd")
		(comment 1 "Grand Teton / footprint 3133 of 6105 (J32), pads 183-228 of 291")
	)
	(layers
		(0 "F.Cu" signal "TOP")
		(4 "In1.Cu" signal "GND")
		(6 "In2.Cu" signal "IN1")
		(8 "In3.Cu" signal "GND1")
		(10 "In4.Cu" signal "IN2")
		(12 "In5.Cu" signal "GND2")
		(14 "In6.Cu" signal "IN3")
		(16 "In7.Cu" signal "GND3")
		(18 "In8.Cu" signal "VCC")
		(20 "In9.Cu" signal "VCC1")
		(22 "In10.Cu" signal "GND4")
		(24 "In11.Cu" signal "IN4")
		(26 "In12.Cu" signal "GND5")
		(28 "In13.Cu" signal "IN5")
		(30 "In14.Cu" signal "GND6")
		(32 "In15.Cu" signal "IN6")
		(34 "In16.Cu" signal "GND7")
		(2 "B.Cu" signal "BOTTOM")
		(9 "F.Adhes" user "F.Adhesive")
		(11 "B.Adhes" user "B.Adhesive")
		(13 "F.Paste" user "Package Geometry/Pastemask Top")
		(15 "B.Paste" user "Package Geometry/Pastemask Bottom")
		(5 "F.SilkS" user "Ref Des/Silkscreen Top")
		(7 "B.SilkS" user "Ref Des/Silkscreen Bottom")
		(1 "F.Mask" user "Board Geometry/Soldermask Top")
		(3 "B.Mask" user "Board Geometry/Soldermask Bottom")
		(17 "Dwgs.User" user "User.Drawings")
		(19 "Cmts.User" user "User.Comments")
		(21 "Eco1.User" user "User.Eco1")
		(23 "Eco2.User" user "User.Eco2")
		(25 "Edge.Cuts" user "Board Geometry/Outline")
		(27 "Margin" user)
		(31 "F.CrtYd" user "Package Geometry/Place Bound Top")
		(29 "B.CrtYd" user "Package Geometry/Place Bound Bottom")
		(35 "F.Fab" user "Ref Des/Assembly Top")
		(33 "B.Fab" user "Ref Des/Assembly Bottom")
	)
	(footprint ""
		(layer "F.Cu")
		(at 206.12608 -258.091686)
		(property "Reference" "J32"
			(at 0.68834 -81.826608 0)
			(unlocked yes)
			(layer "F.SilkS")
			(effects
				(font
					(size 0.7874 0.5842)
					(thickness 0.1524)
				)
				(justify left)
			)
		)
		(property "Value" ""
			(at 0 0 0)
			(layer "F.Fab")
			(effects
				(font
					(size 1.27 1.27)
				)
			)
		)
		(duplicate_pad_numbers_are_jumpers no)
		(pad "183" smd rect
			(at 2.050034 -31.025084 270)
			(size 0.519938 1.4986)
			(layers "F.Cu" "F.Mask" "F.Paste")
			(net "M_H_CPU1_SA_DQ<23>")
		)
		(pad "184" smd rect
			(at 2.050034 -30.174946 270)
			(size 0.519938 1.4986)
			(layers "F.Cu" "F.Mask" "F.Paste")
			(net "GND")
		)
		(pad "185" smd rect
			(at 2.050034 -29.325062 270)
			(size 0.519938 1.4986)
			(layers "F.Cu" "F.Mask" "F.Paste")
			(net "M_H_CPU1_SA_DQ<26>")
		)
		(pad "186" smd rect
			(at 2.050034 -28.474924 270)
			(size 0.519938 1.4986)
			(layers "F.Cu" "F.Mask" "F.Paste")
			(net "GND")
		)
		(pad "187" smd rect
			(at 2.050034 -27.62504 270)
			(size 0.519938 1.4986)
			(layers "F.Cu" "F.Mask" "F.Paste")
			(net "M_H_CPU1_SA_DQ<27>")
		)
		(pad "188" smd rect
			(at 2.050034 -26.774902 270)
			(size 0.519938 1.4986)
			(layers "F.Cu" "F.Mask" "F.Paste")
			(net "GND")
		)
		(pad "189" smd rect
			(at 2.050034 -25.925018 270)
			(size 0.519938 1.4986)
			(layers "F.Cu" "F.Mask" "F.Paste")
			(net "M_H_CPU1_SA_DQS_DN<8>")
		)
		(pad "190" smd rect
			(at 2.050034 -25.07488 270)
			(size 0.519938 1.4986)
			(layers "F.Cu" "F.Mask" "F.Paste")
			(net "M_H_CPU1_SA_DQS_DP<8>")
		)
		(pad "191" smd rect
			(at 2.050034 -24.224996 270)
			(size 0.519938 1.4986)
			(layers "F.Cu" "F.Mask" "F.Paste")
			(net "GND")
		)
		(pad "192" smd rect
			(at 2.050034 -23.375112 270)
			(size 0.519938 1.4986)
			(layers "F.Cu" "F.Mask" "F.Paste")
			(net "M_H_CPU1_SA_DQ<30>")
		)
		(pad "193" smd rect
			(at 2.050034 -22.524974 270)
			(size 0.519938 1.4986)
			(layers "F.Cu" "F.Mask" "F.Paste")
			(net "GND")
		)
		(pad "194" smd rect
			(at 2.050034 -21.67509 270)
			(size 0.519938 1.4986)
			(layers "F.Cu" "F.Mask" "F.Paste")
			(net "M_H_CPU1_SA_DQ<31>")
		)
		(pad "195" smd rect
			(at 2.050034 -20.824952 270)
			(size 0.519938 1.4986)
			(layers "F.Cu" "F.Mask" "F.Paste")
			(net "GND")
		)
		(pad "196" smd rect
			(at 2.050034 -19.975068 270)
			(size 0.519938 1.4986)
			(layers "F.Cu" "F.Mask" "F.Paste")
			(net "M_H_CPU1_SA_CB<2>")
		)
		(pad "197" smd rect
			(at 2.050034 -19.12493 270)
			(size 0.519938 1.4986)
			(layers "F.Cu" "F.Mask" "F.Paste")
			(net "GND")
		)
		(pad "198" smd rect
			(at 2.050034 -18.275046 270)
			(size 0.519938 1.4986)
			(layers "F.Cu" "F.Mask" "F.Paste")
			(net "M_H_CPU1_SA_CB<3>")
		)
		(pad "199" smd rect
			(at 2.050034 -17.424908 270)
			(size 0.519938 1.4986)
			(layers "F.Cu" "F.Mask" "F.Paste")
			(net "GND")
		)
		(pad "200" smd rect
			(at 2.050034 -16.575024 270)
			(size 0.519938 1.4986)
			(layers "F.Cu" "F.Mask" "F.Paste")
			(net "M_H_CPU1_SA_DQS_DN<9>")
		)
		(pad "201" smd rect
			(at 2.050034 -15.724886 270)
			(size 0.519938 1.4986)
			(layers "F.Cu" "F.Mask" "F.Paste")
			(net "M_H_CPU1_SA_DQS_DP<9>")
		)
		(pad "202" smd rect
			(at 2.050034 -14.875002 270)
			(size 0.519938 1.4986)
			(layers "F.Cu" "F.Mask" "F.Paste")
			(net "GND")
		)
		(pad "203" smd rect
			(at 2.050034 -14.025118 270)
			(size 0.519938 1.4986)
			(layers "F.Cu" "F.Mask" "F.Paste")
			(net "M_H_CPU1_SA_CB<6>")
		)
		(pad "204" smd rect
			(at 2.050034 -13.17498 270)
			(size 0.519938 1.4986)
			(layers "F.Cu" "F.Mask" "F.Paste")
			(net "GND")
		)
		(pad "205" smd rect
			(at 2.050034 -12.325096 270)
			(size 0.519938 1.4986)
			(layers "F.Cu" "F.Mask" "F.Paste")
			(net "M_H_CPU1_SA_CB<7>")
		)
		(pad "206" smd rect
			(at 2.050034 -11.474958 270)
			(size 0.519938 1.4986)
			(layers "F.Cu" "F.Mask" "F.Paste")
			(net "GND")
		)
		(pad "207" smd rect
			(at 2.050034 -10.625074 270)
			(size 0.519938 1.4986)
			(layers "F.Cu" "F.Mask" "F.Paste")
			(net "RST_M_GH_CPU1_FPGA_N")
		)
		(pad "208" smd rect
			(at 2.050034 -9.774936 270)
			(size 0.519938 1.4986)
			(layers "F.Cu" "F.Mask" "F.Paste")
			(net "GND")
		)
		(pad "209" smd rect
			(at 2.050034 -8.925052 270)
			(size 0.519938 1.4986)
			(layers "F.Cu" "F.Mask" "F.Paste")
			(net "M_H_CPU1_SA_CS_N<3>")
		)
		(pad "210" smd rect
			(at 2.050034 -8.074914 270)
			(size 0.519938 1.4986)
			(layers "F.Cu" "F.Mask" "F.Paste")
			(net "GND")
		)
		(pad "211" smd rect
			(at 2.050034 -7.22503 270)
			(size 0.519938 1.4986)
			(layers "F.Cu" "F.Mask" "F.Paste")
			(net "M_H_CPU1_SA_CA<1>")
		)
		(pad "212" smd rect
			(at 2.050034 -6.374892 270)
			(size 0.519938 1.4986)
			(layers "F.Cu" "F.Mask" "F.Paste")
			(net "GND")
		)
		(pad "213" smd rect
			(at 2.050034 -5.525008 270)
			(size 0.519938 1.4986)
			(layers "F.Cu" "F.Mask" "F.Paste")
			(net "M_H_CPU1_SA_CA<3>")
		)
		(pad "214" smd rect
			(at 2.050034 -4.675124 270)
			(size 0.519938 1.4986)
			(layers "F.Cu" "F.Mask" "F.Paste")
			(net "GND")
		)
		(pad "215" smd rect
			(at 2.050034 -3.824986 270)
			(size 0.519938 1.4986)
			(layers "F.Cu" "F.Mask" "F.Paste")
			(net "M_H_CPU1_SA_CA<5>")
		)
		(pad "216" smd rect
			(at 2.050034 -2.975102 270)
			(size 0.519938 1.4986)
			(layers "F.Cu" "F.Mask" "F.Paste")
			(net "GND")
		)
		(pad "217" smd rect
			(at 2.050034 -2.124964 270)
			(size 0.519938 1.4986)
			(layers "F.Cu" "F.Mask" "F.Paste")
			(net "M_H_CPU1_CLK_DP<1>")
		)
		(pad "218" smd rect
			(at 2.050034 -1.27508 270)
			(size 0.519938 1.4986)
			(layers "F.Cu" "F.Mask" "F.Paste")
			(net "M_H_CPU1_CLK_DN<1>")
		)
		(pad "219" smd rect
			(at 2.050034 -0.424942 270)
			(size 0.519938 1.4986)
			(layers "F.Cu" "F.Mask" "F.Paste")
			(net "GND")
		)
		(pad "220" smd rect
			(at 2.050034 5.525008 270)
			(size 0.519938 1.4986)
			(layers "F.Cu" "F.Mask" "F.Paste")
			(net "TP_CHH_CPU1_DIMM2_FRU_4")
		)
		(pad "221" smd rect
			(at 2.050034 6.374892 270)
			(size 0.519938 1.4986)
			(layers "F.Cu" "F.Mask" "F.Paste")
			(net "M_H_CPU1_SB_CA<1>")
		)
		(pad "222" smd rect
			(at 2.050034 7.22503 270)
			(size 0.519938 1.4986)
			(layers "F.Cu" "F.Mask" "F.Paste")
			(net "GND")
		)
		(pad "223" smd rect
			(at 2.050034 8.074914 270)
			(size 0.519938 1.4986)
			(layers "F.Cu" "F.Mask" "F.Paste")
			(net "M_H_CPU1_SB_CA<3>")
		)
		(pad "224" smd rect
			(at 2.050034 8.925052 270)
			(size 0.519938 1.4986)
			(layers "F.Cu" "F.Mask" "F.Paste")
			(net "GND")
		)
		(pad "225" smd rect
			(at 2.050034 9.774936 270)
			(size 0.519938 1.4986)
			(layers "F.Cu" "F.Mask" "F.Paste")
			(net "M_H_CPU1_SB_CA<5>")
		)
		(pad "226" smd rect
			(at 2.050034 10.625074 270)
			(size 0.519938 1.4986)
			(layers "F.Cu" "F.Mask" "F.Paste")
			(net "GND")
		)
		(pad "227" smd rect
			(at 2.050034 11.474958 270)
			(size 0.519938 1.4986)
			(layers "F.Cu" "F.Mask" "F.Paste")
			(net "M_H_CPU1_SB_PAR")
		)
		(pad "228" smd rect
			(at 2.050034 12.325096 270)
			(size 0.519938 1.4986)
			(layers "F.Cu" "F.Mask" "F.Paste")
			(net "GND")
		)
	)
)
